# T6G (Grand Teton) — schematic netlist excerpt (pin names and nets, part order shuffled) for the footprints in the layout excerpt that follows; sources: Cadence DE-HDL packaged netlist, KiCad conversion of 04192023_DAF0TMB3IC0_F0TG_MB_C_brd_V02_OCP.brd

C46  Q_CAP_DIFFBUS  DIFF BUS_0.22UF 6.3V 20% X6S  pkg C0201  page 65 : \1\ = P5E_CPU0_G3_TX_C_DN<7> ; \2\ = P5E_CPU0_G3_TX_DN<7>
D99  Q_LED  IC  pkg SMLF  page 254 : A = LED_P3V3 ; C = GND
PC2238  Q_CAP  0.1UF 25V 10% X7R  pkg 0402  page 152 : A = P12V_SCM_R ; B = GND

(kicad_pcb
	(version 20260206)
	(generator "pcbnew")
	(generator_version "10.0")
	(general
		(thickness 1.6)
		(legacy_teardrops no)
	)
	(paper "A4")
	(title_block
		(title "04192023_DAF0TMB3IC0_F0TG_MB_C_brd_V02_OCP.brd")
		(comment 1 "Grand Teton / footprints 2555-2557 of 8354")
	)
	(layers
		(0 "F.Cu" signal "TOP")
		(4 "In1.Cu" signal "GND")
		(6 "In2.Cu" signal "IN1")
		(8 "In3.Cu" signal "GND1")
		(10 "In4.Cu" signal "IN2")
		(12 "In5.Cu" signal "GND2")
		(14 "In6.Cu" signal "IN3")
		(16 "In7.Cu" signal "GND3")
		(18 "In8.Cu" signal "VCC")
		(20 "In9.Cu" signal "VCC1")
		(22 "In10.Cu" signal "GND4")
		(24 "In11.Cu" signal "IN4")
		(26 "In12.Cu" signal "GND5")
		(28 "In13.Cu" signal "IN5")
		(30 "In14.Cu" signal "GND6")
		(32 "In15.Cu" signal "IN6")
		(34 "In16.Cu" signal "GND7")
		(2 "B.Cu" signal "BOTTOM")
		(9 "F.Adhes" user "F.Adhesive")
		(11 "B.Adhes" user "B.Adhesive")
		(13 "F.Paste" user "Package Geometry/Pastemask Top")
		(15 "B.Paste" user "Package Geometry/Pastemask Bottom")
		(5 "F.SilkS" user "Ref Des/Silkscreen Top")
		(7 "B.SilkS" user "Ref Des/Silkscreen Bottom")
		(1 "F.Mask" user "Board Geometry/Soldermask Top")
		(3 "B.Mask" user "Board Geometry/Soldermask Bottom")
		(17 "Dwgs.User" user "User.Drawings")
		(19 "Cmts.User" user "User.Comments")
		(21 "Eco1.User" user "User.Eco1")
		(23 "Eco2.User" user "User.Eco2")
		(25 "Edge.Cuts" user "Board Geometry/Outline")
		(27 "Margin" user)
		(31 "F.CrtYd" user "Package Geometry/Place Bound Top")
		(29 "B.CrtYd" user "Package Geometry/Place Bound Bottom")
		(35 "F.Fab" user "Ref Des/Assembly Top")
		(33 "B.Fab" user "Ref Des/Assembly Bottom")
	)
	(footprint ""
		(layer "F.Cu")
		(at 175.82388 -19.548348 180)
		(property "Reference" "PC2238"
			(at 0 0 180)
			(layer "F.SilkS")
			(hide yes)
			(effects
				(font
					(size 1.27 1.27)
				)
			)
		)
		(property "Value" ""
			(at 0 0 180)
			(layer "F.Fab")
			(effects
				(font
					(size 1.27 1.27)
				)
			)
		)
		(duplicate_pad_numbers_are_jumpers no)
		(fp_line
			(start 0.7874 0.4064)
			(end -0.7874 0.4064)
			(stroke
				(width 0.1524)
				(type default)
			)
			(layer "F.SilkS")
		)
		(fp_line
			(start 0.7874 -0.4064)
			(end 0.7874 0.4064)
			(stroke
				(width 0.1524)
				(type default)
			)
			(layer "F.SilkS")
		)
		(fp_line
			(start -0.7874 0.4064)
			(end -0.7874 -0.4064)
			(stroke
				(width 0.1524)
				(type default)
			)
			(layer "F.SilkS")
		)
		(fp_line
			(start -0.7874 -0.4064)
			(end 0.7874 -0.4064)
			(stroke
				(width 0.1524)
				(type default)
			)
			(layer "F.SilkS")
		)
		(fp_line
			(start 0.67945 0.3048)
			(end 0.120396 0.3048)
			(stroke
				(width 0.1)
				(type default)
			)
			(layer "F.Fab")
		)
		(fp_line
			(start 0.67945 -0.3048)
			(end 0.67945 0.3048)
			(stroke
				(width 0.1)
				(type default)
			)
			(layer "F.Fab")
		)
		(fp_line
			(start 0.12065 -0.2794)
			(end 0.12065 -0.3048)
			(stroke
				(width 0.1)
				(type default)
			)
			(layer "F.Fab")
		)
		(fp_line
			(start 0.12065 -0.3048)
			(end 0.67945 -0.3048)
			(stroke
				(width 0.1)
				(type default)
			)
			(layer "F.Fab")
		)
		(fp_line
			(start 0.120396 0.3048)
			(end 0.120396 0.2794)
			(stroke
				(width 0.1)
				(type default)
			)
			(layer "F.Fab")
		)
		(fp_line
			(start 0.120396 0.2794)
			(end -0.12065 0.2794)
			(stroke
				(width 0.1)
				(type default)
			)
			(layer "F.Fab")
		)
		(fp_line
			(start -0.12065 0.3048)
			(end -0.67945 0.3048)
			(stroke
				(width 0.1)
				(type default)
			)
			(layer "F.Fab")
		)
		(fp_line
			(start -0.12065 0.2794)
			(end -0.12065 0.3048)
			(stroke
				(width 0.1)
				(type default)
			)
			(layer "F.Fab")
		)
		(fp_line
			(start -0.12065 -0.2794)
			(end 0.12065 -0.2794)
			(stroke
				(width 0.1)
				(type default)
			)
			(layer "F.Fab")
		)
		(fp_line
			(start -0.12065 -0.305054)
			(end -0.12065 -0.2794)
			(stroke
				(width 0.1)
				(type default)
			)
			(layer "F.Fab")
		)
		(fp_line
			(start -0.67945 0.3048)
			(end -0.67945 -0.305054)
			(stroke
				(width 0.1)
				(type default)
			)
			(layer "F.Fab")
		)
		(fp_line
			(start -0.67945 -0.305054)
			(end -0.12065 -0.305054)
			(stroke
				(width 0.1)
				(type default)
			)
			(layer "F.Fab")
		)
		(pad "1" smd circle
			(at -0.40005 0 180)
			(size 0 0)
			(layers "F.Cu" "F.Mask" "F.Paste")
			(net "P12V_SCM_R")
		)
		(pad "2" smd circle
			(at 0.40005 0 180)
			(size 0 0)
			(layers "F.Cu" "F.Mask" "F.Paste")
			(net "GND")
		)
	)
	(footprint ""
		(layer "F.Cu")
		(at 412.359348 -16.100298 90)
		(property "Reference" "C46"
			(at 0 0 90)
			(layer "F.SilkS")
			(hide yes)
			(effects
				(font
					(size 1.27 1.27)
				)
			)
		)
		(property "Value" ""
			(at 0 0 90)
			(layer "F.Fab")
			(effects
				(font
					(size 1.27 1.27)
				)
			)
		)
		(duplicate_pad_numbers_are_jumpers no)
		(fp_line
			(start 0.299974 -0.150114)
			(end 0.299974 0.150114)
			(stroke
				(width 0.1)
				(type default)
			)
			(layer "F.Fab")
		)
		(fp_line
			(start -0.299974 -0.150114)
			(end 0.299974 -0.150114)
			(stroke
				(width 0.1)
				(type default)
			)
			(layer "F.Fab")
		)
		(fp_line
			(start 0.299974 0.150114)
			(end -0.299974 0.150114)
			(stroke
				(width 0.1)
				(type default)
			)
			(layer "F.Fab")
		)
		(fp_line
			(start -0.299974 0.150114)
			(end -0.299974 -0.150114)
			(stroke
				(width 0.1)
				(type default)
			)
			(layer "F.Fab")
		)
		(pad "1" smd rect
			(at -0.2667 0 90)
			(size 0.3048 0.381)
			(layers "F.Cu" "F.Mask" "F.Paste")
			(net "P5E_CPU0_G3_TX_C_DN<7>")
		)
		(pad "2" smd rect
			(at 0.2667 0 90)
			(size 0.3048 0.381)
			(layers "F.Cu" "F.Mask" "F.Paste")
			(net "P5E_CPU0_G3_TX_DN<7>")
		)
	)
	(footprint ""
		(layer "F.Cu")
		(at 316.507876 -70.098412 90)
		(property "Reference" "D99"
			(at -3.934714 -0.691642 90)
			(unlocked yes)
			(layer "F.SilkS")
			(effects
				(font
					(size 0.7874 0.5842)
					(thickness 0.1524)
				)
				(justify left)
			)
		)
		(property "Value" ""
			(at 0 0 90)
			(layer "F.Fab")
			(effects
				(font
					(size 1.27 1.27)
				)
			)
		)
		(duplicate_pad_numbers_are_jumpers no)
		(fp_line
			(start 1.16078 -0.4826)
			(end 1.16078 0.4826)
			(stroke
				(width 0.1524)
				(type default)
			)
			(layer "F.SilkS")
		)
		(fp_line
			(start 1.03378 -0.4826)
			(end 1.03378 0.4826)
			(stroke
				(width 0.1524)
				(type default)
			)
			(layer "F.SilkS")
		)
		(fp_line
			(start 0.90678 -0.4826)
			(end 0.90678 0.4826)
			(stroke
				(width 0.1524)
				(type default)
			)
			(layer "F.SilkS")
		)
		(fp_line
			(start -0.64008 -0.4826)
			(end 1.16078 -0.4826)
			(stroke
				(width 0.1524)
				(type default)
			)
			(layer "F.SilkS")
		)
		(fp_line
			(start -0.79248 -0.4826)
			(end 1.03378 -0.4826)
			(stroke
				(width 0.1524)
				(type default)
			)
			(layer "F.SilkS")
		)
		(fp_line
			(start -0.89408 -0.4826)
			(end 0.90678 -0.4826)
			(stroke
				(width 0.1524)
				(type default)
			)
			(layer "F.SilkS")
		)
		(fp_line
			(start 1.16078 0.4826)
			(end -0.64008 0.4826)
			(stroke
				(width 0.1524)
				(type default)
			)
			(layer "F.SilkS")
		)
		(fp_line
			(start 1.03378 0.4826)
			(end -0.79248 0.4826)
			(stroke
				(width 0.1524)
				(type default)
			)
			(layer "F.SilkS")
		)
		(fp_line
			(start 0.90678 0.4826)
			(end -0.90678 0.4826)
			(stroke
				(width 0.1524)
				(type default)
			)
			(layer "F.SilkS")
		)
		(fp_line
			(start -0.90678 0.4826)
			(end -0.90678 -0.4699)
			(stroke
				(width 0.1524)
				(type default)
			)
			(layer "F.SilkS")
		)
		(fp_line
			(start 0.499872 -0.249936)
			(end 0.499872 0.249936)
			(stroke
				(width 0.1)
				(type default)
			)
			(layer "F.Fab")
		)
		(fp_line
			(start -0.499872 -0.249936)
			(end 0.499872 -0.249936)
			(stroke
				(width 0.1)
				(type default)
			)
			(layer "F.Fab")
		)
		(fp_line
			(start 0.499872 0.249936)
			(end -0.499872 0.249936)
			(stroke
				(width 0.1)
				(type default)
			)
			(layer "F.Fab")
		)
		(fp_line
			(start -0.499872 0.249936)
			(end -0.499872 -0.249936)
			(stroke
				(width 0.1)
				(type default)
			)
			(layer "F.Fab")
		)
		(pad "A" smd rect
			(at -0.47498 0 90)
			(size 0.6096 0.7112)
			(layers "F.Cu" "F.Mask" "F.Paste")
			(net "LED_P3V3")
		)
		(pad "C" smd rect
			(at 0.47498 0 90)
			(size 0.6096 0.7112)
			(layers "F.Cu" "F.Mask" "F.Paste")
			(net "GND")
		)
	)
)
